# S9S_MB_2U (Grand Teton) — schematic netlist excerpt (pin names and nets, part order shuffled) for the footprints in the layout excerpt that follows; sources: Cadence DE-HDL packaged netlist, KiCad conversion of 03242023_DA0F0TMBIJ0_F0T_Motherboard_J_brd_V01_OCP.brd

C716  Q_CAP_DIFFBUS  DIFF BUS_0.22UF 6.3V 20% X6S  pkg C0201  page 176 : \1\ = P5E_CPU1_PE0_TX_C_DN<12> ; \2\ = P5E_CPU1_PE0_TX_DN<12>
R3055  Q_RES  1K 1% CHIP  pkg 0402LF  page 239 : A = P3V3_AUX ; B = PU_GTL2014_BMC_JTAG_DIR_1
R2489  Q_RES  33.2 1% CHIP  pkg 0402LF  page 155 : A = IRQ_LVC3_WAKE_BUF_N ; B = IRQ_LVC3_WAKE_N

(kicad_pcb
	(version 20260206)
	(generator "pcbnew")
	(generator_version "10.0")
	(general
		(thickness 1.6)
		(legacy_teardrops no)
	)
	(paper "A4")
	(title_block
		(title "03242023_DA0F0TMBIJ0_F0T_Motherboard_J_brd_V01_OCP.brd")
		(comment 1 "Grand Teton / footprints 2129-2131 of 6105")
	)
	(layers
		(0 "F.Cu" signal "TOP")
		(4 "In1.Cu" signal "GND")
		(6 "In2.Cu" signal "IN1")
		(8 "In3.Cu" signal "GND1")
		(10 "In4.Cu" signal "IN2")
		(12 "In5.Cu" signal "GND2")
		(14 "In6.Cu" signal "IN3")
		(16 "In7.Cu" signal "GND3")
		(18 "In8.Cu" signal "VCC")
		(20 "In9.Cu" signal "VCC1")
		(22 "In10.Cu" signal "GND4")
		(24 "In11.Cu" signal "IN4")
		(26 "In12.Cu" signal "GND5")
		(28 "In13.Cu" signal "IN5")
		(30 "In14.Cu" signal "GND6")
		(32 "In15.Cu" signal "IN6")
		(34 "In16.Cu" signal "GND7")
		(2 "B.Cu" signal "BOTTOM")
		(9 "F.Adhes" user "F.Adhesive")
		(11 "B.Adhes" user "B.Adhesive")
		(13 "F.Paste" user "Package Geometry/Pastemask Top")
		(15 "B.Paste" user "Package Geometry/Pastemask Bottom")
		(5 "F.SilkS" user "Ref Des/Silkscreen Top")
		(7 "B.SilkS" user "Ref Des/Silkscreen Bottom")
		(1 "F.Mask" user "Board Geometry/Soldermask Top")
		(3 "B.Mask" user "Board Geometry/Soldermask Bottom")
		(17 "Dwgs.User" user "User.Drawings")
		(19 "Cmts.User" user "User.Comments")
		(21 "Eco1.User" user "User.Eco1")
		(23 "Eco2.User" user "User.Eco2")
		(25 "Edge.Cuts" user "Board Geometry/Outline")
		(27 "Margin" user)
		(31 "F.CrtYd" user "Package Geometry/Place Bound Top")
		(29 "B.CrtYd" user "Package Geometry/Place Bound Bottom")
		(35 "F.Fab" user "Ref Des/Assembly Top")
		(33 "B.Fab" user "Ref Des/Assembly Bottom")
	)
	(footprint ""
		(layer "F.Cu")
		(at 306.263294 -15.50924 180)
		(property "Reference" "R2489"
			(at 0 0 180)
			(layer "F.SilkS")
			(hide yes)
			(effects
				(font
					(size 1.27 1.27)
				)
			)
		)
		(property "Value" ""
			(at 0 0 180)
			(layer "F.Fab")
			(effects
				(font
					(size 1.27 1.27)
				)
			)
		)
		(duplicate_pad_numbers_are_jumpers no)
		(fp_line
			(start 0.7874 0.4064)
			(end -0.7874 0.4064)
			(stroke
				(width 0.1524)
				(type default)
			)
			(layer "F.SilkS")
		)
		(fp_line
			(start 0.7874 -0.4064)
			(end 0.7874 0.4064)
			(stroke
				(width 0.1524)
				(type default)
			)
			(layer "F.SilkS")
		)
		(fp_line
			(start -0.7874 0.4064)
			(end -0.7874 -0.4064)
			(stroke
				(width 0.1524)
				(type default)
			)
			(layer "F.SilkS")
		)
		(fp_line
			(start -0.7874 -0.4064)
			(end 0.7874 -0.4064)
			(stroke
				(width 0.1524)
				(type default)
			)
			(layer "F.SilkS")
		)
		(fp_line
			(start 0.67945 0.3048)
			(end 0.120396 0.3048)
			(stroke
				(width 0.1)
				(type default)
			)
			(layer "F.Fab")
		)
		(fp_line
			(start 0.67945 -0.3048)
			(end 0.67945 0.3048)
			(stroke
				(width 0.1)
				(type default)
			)
			(layer "F.Fab")
		)
		(fp_line
			(start 0.12065 -0.2794)
			(end 0.12065 -0.3048)
			(stroke
				(width 0.1)
				(type default)
			)
			(layer "F.Fab")
		)
		(fp_line
			(start 0.12065 -0.3048)
			(end 0.67945 -0.3048)
			(stroke
				(width 0.1)
				(type default)
			)
			(layer "F.Fab")
		)
		(fp_line
			(start 0.120396 0.3048)
			(end 0.120396 0.2794)
			(stroke
				(width 0.1)
				(type default)
			)
			(layer "F.Fab")
		)
		(fp_line
			(start 0.120396 0.2794)
			(end -0.12065 0.2794)
			(stroke
				(width 0.1)
				(type default)
			)
			(layer "F.Fab")
		)
		(fp_line
			(start -0.12065 0.3048)
			(end -0.67945 0.3048)
			(stroke
				(width 0.1)
				(type default)
			)
			(layer "F.Fab")
		)
		(fp_line
			(start -0.12065 0.2794)
			(end -0.12065 0.3048)
			(stroke
				(width 0.1)
				(type default)
			)
			(layer "F.Fab")
		)
		(fp_line
			(start -0.12065 -0.2794)
			(end 0.12065 -0.2794)
			(stroke
				(width 0.1)
				(type default)
			)
			(layer "F.Fab")
		)
		(fp_line
			(start -0.12065 -0.305054)
			(end -0.12065 -0.2794)
			(stroke
				(width 0.1)
				(type default)
			)
			(layer "F.Fab")
		)
		(fp_line
			(start -0.67945 0.3048)
			(end -0.67945 -0.305054)
			(stroke
				(width 0.1)
				(type default)
			)
			(layer "F.Fab")
		)
		(fp_line
			(start -0.67945 -0.305054)
			(end -0.12065 -0.305054)
			(stroke
				(width 0.1)
				(type default)
			)
			(layer "F.Fab")
		)
		(pad "1" smd circle
			(at -0.40005 0 180)
			(size 0 0)
			(layers "F.Cu" "F.Mask" "F.Paste")
			(net "IRQ_LVC3_WAKE_BUF_N")
		)
		(pad "2" smd circle
			(at 0.40005 0 180)
			(size 0 0)
			(layers "F.Cu" "F.Mask" "F.Paste")
			(net "IRQ_LVC3_WAKE_N")
		)
	)
	(footprint ""
		(layer "F.Cu")
		(at 368.243358 -92.962984 90)
		(property "Reference" "R3055"
			(at 0 0 90)
			(layer "F.SilkS")
			(hide yes)
			(effects
				(font
					(size 1.27 1.27)
				)
			)
		)
		(property "Value" ""
			(at 0 0 90)
			(layer "F.Fab")
			(effects
				(font
					(size 1.27 1.27)
				)
			)
		)
		(duplicate_pad_numbers_are_jumpers no)
		(fp_line
			(start 0.7874 -0.4064)
			(end 0.7874 0.4064)
			(stroke
				(width 0.1524)
				(type default)
			)
			(layer "F.SilkS")
		)
		(fp_line
			(start -0.7874 -0.4064)
			(end 0.7874 -0.4064)
			(stroke
				(width 0.1524)
				(type default)
			)
			(layer "F.SilkS")
		)
		(fp_line
			(start 0.7874 0.4064)
			(end -0.7874 0.4064)
			(stroke
				(width 0.1524)
				(type default)
			)
			(layer "F.SilkS")
		)
		(fp_line
			(start -0.7874 0.4064)
			(end -0.7874 -0.4064)
			(stroke
				(width 0.1524)
				(type default)
			)
			(layer "F.SilkS")
		)
		(fp_line
			(start -0.12065 -0.305054)
			(end -0.12065 -0.2794)
			(stroke
				(width 0.1)
				(type default)
			)
			(layer "F.Fab")
		)
		(fp_line
			(start -0.67945 -0.305054)
			(end -0.12065 -0.305054)
			(stroke
				(width 0.1)
				(type default)
			)
			(layer "F.Fab")
		)
		(fp_line
			(start 0.67945 -0.3048)
			(end 0.67945 0.3048)
			(stroke
				(width 0.1)
				(type default)
			)
			(layer "F.Fab")
		)
		(fp_line
			(start 0.12065 -0.3048)
			(end 0.67945 -0.3048)
			(stroke
				(width 0.1)
				(type default)
			)
			(layer "F.Fab")
		)
		(fp_line
			(start 0.12065 -0.2794)
			(end 0.12065 -0.3048)
			(stroke
				(width 0.1)
				(type default)
			)
			(layer "F.Fab")
		)
		(fp_line
			(start -0.12065 -0.2794)
			(end 0.12065 -0.2794)
			(stroke
				(width 0.1)
				(type default)
			)
			(layer "F.Fab")
		)
		(fp_line
			(start 0.120396 0.2794)
			(end -0.12065 0.2794)
			(stroke
				(width 0.1)
				(type default)
			)
			(layer "F.Fab")
		)
		(fp_line
			(start -0.12065 0.2794)
			(end -0.12065 0.3048)
			(stroke
				(width 0.1)
				(type default)
			)
			(layer "F.Fab")
		)
		(fp_line
			(start 0.67945 0.3048)
			(end 0.120396 0.3048)
			(stroke
				(width 0.1)
				(type default)
			)
			(layer "F.Fab")
		)
		(fp_line
			(start 0.120396 0.3048)
			(end 0.120396 0.2794)
			(stroke
				(width 0.1)
				(type default)
			)
			(layer "F.Fab")
		)
		(fp_line
			(start -0.12065 0.3048)
			(end -0.67945 0.3048)
			(stroke
				(width 0.1)
				(type default)
			)
			(layer "F.Fab")
		)
		(fp_line
			(start -0.67945 0.3048)
			(end -0.67945 -0.305054)
			(stroke
				(width 0.1)
				(type default)
			)
			(layer "F.Fab")
		)
		(pad "1" smd circle
			(at -0.40005 0 90)
			(size 0 0)
			(layers "F.Cu" "F.Mask" "F.Paste")
			(net "P3V3_AUX")
		)
		(pad "2" smd circle
			(at 0.40005 0 90)
			(size 0 0)
			(layers "F.Cu" "F.Mask" "F.Paste")
			(net "PU_GTL2014_BMC_JTAG_DIR_1")
		)
	)
	(footprint ""
		(layer "F.Cu")
		(at 57.144158 -402.371052 -90)
		(property "Reference" "C716"
			(at 0 0 270)
			(layer "F.SilkS")
			(hide yes)
			(effects
				(font
					(size 1.27 1.27)
				)
			)
		)
		(property "Value" ""
			(at 0 0 270)
			(layer "F.Fab")
			(effects
				(font
					(size 1.27 1.27)
				)
			)
		)
		(duplicate_pad_numbers_are_jumpers no)
		(fp_line
			(start -0.299974 0.150114)
			(end -0.299974 -0.150114)
			(stroke
				(width 0.1)
				(type default)
			)
			(layer "F.Fab")
		)
		(fp_line
			(start 0.299974 0.150114)
			(end -0.299974 0.150114)
			(stroke
				(width 0.1)
				(type default)
			)
			(layer "F.Fab")
		)
		(fp_line
			(start -0.299974 -0.150114)
			(end 0.299974 -0.150114)
			(stroke
				(width 0.1)
				(type default)
			)
			(layer "F.Fab")
		)
		(fp_line
			(start 0.299974 -0.150114)
			(end 0.299974 0.150114)
			(stroke
				(width 0.1)
				(type default)
			)
			(layer "F.Fab")
		)
		(pad "1" smd rect
			(at -0.2667 0 270)
			(size 0.3048 0.381)
			(layers "F.Cu" "F.Mask" "F.Paste")
			(net "P5E_CPU1_PE0_TX_C_DN<12>")
		)
		(pad "2" smd rect
			(at 0.2667 0 270)
			(size 0.3048 0.381)
			(layers "F.Cu" "F.Mask" "F.Paste")
			(net "P5E_CPU1_PE0_TX_DN<12>")
		)
	)
)
